#ISCELL
  mstr_misc dns *
  *
#ISCELL
  pure_quanta quanta_title_block_c *
  *
#CELL
  pure_quanta 74cbtlv3126pw *
  page336_i1
#CELL
  pure_quanta q_res *
  page336_i100
#CELL
  pure_quanta q_res *
  page336_i101
#CELL
  pure_quanta q_res *
  page336_i102
#CELL
  pure_quanta q_res *
  page336_i103
#CELL
  pure_quanta q_res *
  page336_i104
#ISCELL
  standard offpage *
  page336_i110
#ISCELL
  standard offpage *
  page336_i111
#ISCELL
  standard offpage *
  page336_i112
#CELL
  pure_quanta q_res *
  page336_i119
#ISCELL
  standard offpage *
  page336_i120
#CELL
  pure_quanta q_res *
  page336_i122
#CELL
  pure_quanta q_res *
  page336_i123
#CELL
  pure_quanta q_res *
  page336_i124
#ISCELL
  pure_quanta_power universal_gnd *
  page336_i125
#ISCELL
  standard offpage *
  page336_i128
#CELL
  pure_quanta q_res *
  page336_i129
#ISCELL
  pure_quanta_power universal_gnd *
  page336_i130
#CELL
  pure_quanta q_res *
  page336_i131
#CELL
  pure_quanta q_res *
  page336_i132
#CELL
  pure_quanta q_res *
  page336_i133
#CELL
  pure_quanta q_res *
  page336_i134
#CELL
  pure_quanta q_res *
  page336_i135
#CELL
  pure_quanta q_res *
  page336_i136
#ISCELL
  standard offpage *
  page336_i137
#ISCELL
  standard offpage *
  page336_i138
#ISCELL
  standard offpage *
  page336_i139
#ISCELL
  standard offpage *
  page336_i140
#ISCELL
  standard offpage *
  page336_i141
#ISCELL
  standard offpage *
  page336_i142
#ISCELL
  standard offpage *
  page336_i143
#ISCELL
  standard offpage *
  page336_i145
#ISCELL
  pure_quanta_power universal_gnd *
  page336_i146
#CELL
  pure_quanta q_cap *
  page336_i147
#ISCELL
  pure_quanta_power universal_gnd *
  page336_i15
#ISCELL
  pure_quanta_power universal_power *
  page336_i150
#ISCELL
  pure_quanta_power universal_gnd *
  page336_i151
#CELL
  pure_quanta q_res *
  page336_i152
#CELL
  pure_quanta q_res *
  page336_i153
#ISCELL
  standard offpage *
  page336_i154
#CELL
  pure_quanta q_res *
  page336_i156
#CELL
  pure_quanta 74lvc1g126se7 *
  page336_i157
#ISCELL
  pure_quanta_power universal_gnd *
  page336_i158
#CELL
  pure_quanta 74lvc1g126se7 *
  page336_i159
#CELL
  pure_quanta q_cap *
  page336_i16
#CELL
  pure_quanta q_res *
  page336_i160
#ISCELL
  standard offpage *
  page336_i161
#ISCELL
  pure_quanta_power universal_gnd *
  page336_i162
#ISCELL
  standard offpage *
  page336_i163
#CELL
  pure_quanta q_res *
  page336_i164
#CELL
  pure_quanta q_res *
  page336_i165
#CELL
  pure_quanta 74cbtlv3126pw *
  page336_i2
#ISCELL
  standard offpage *
  page336_i35
#ISCELL
  standard offpage *
  page336_i36
#ISCELL
  standard offpage *
  page336_i37
#ISCELL
  standard offpage *
  page336_i38
#ISCELL
  standard offpage *
  page336_i39
#ISCELL
  standard offpage *
  page336_i40
#ISCELL
  standard offpage *
  page336_i41
#ISCELL
  standard offpage *
  page336_i42
#ISCELL
  pure_quanta_power universal_power *
  page336_i43
#ISCELL
  pure_quanta_power universal_gnd *
  page336_i44
#ISCELL
  pure_quanta_power universal_gnd *
  page336_i45
#ISCELL
  pure_quanta_power universal_power *
  page336_i46
#CELL
  pure_quanta q_cap *
  page336_i47
#ISCELL
  pure_quanta_power universal_gnd *
  page336_i48
#ISCELL
  pure_quanta_power universal_power *
  page336_i54
#CELL
  pure_quanta q_res *
  page336_i56
#ISCELL
  pure_quanta_power universal_gnd *
  page336_i57
#ISCELL
  pure_quanta_power universal_gnd *
  page336_i58
#CELL
  pure_quanta q_cap *
  page336_i59
#ISCELL
  standard offpage *
  page336_i61
#ISCELL
  standard offpage *
  page336_i62
#ISCELL
  standard offpage *
  page336_i64
#ISCELL
  standard offpage *
  page336_i65
#ISCELL
  standard offpage *
  page336_i66
#ISCELL
  standard offpage *
  page336_i78
#ISCELL
  standard offpage *
  page336_i79
#ISCELL
  standard offpage *
  page336_i80
#ISCELL
  standard offpage *
  page336_i81
#CELL
  pure_quanta q_res *
  page336_i98
#CELL
  pure_quanta q_res *
  page336_i99
